# S9S_MB_2U (Grand Teton) — schematic netlist excerpt (pin names and nets, part order shuffled) for the footprints in the layout excerpt that follows; sources: Cadence DE-HDL packaged netlist, KiCad conversion of 03242023_DA0F0TMBIJ0_F0T_Motherboard_J_brd_V01_OCP.brd

C382  Q_CAP  47UF 4V 20% X6S  pkg C0805  page 75 : A = PVCCIN_CPU0 ; B = GND
PC2170  Q_CAPP  330UF 2.5V +10/-35% SPCAP  pkg SMLF  page 272 : A = PVCCFA_EHV_FIVRA_CPU0 ; B = GND
R319  Q_RES  10K 1% CHIP  pkg 0402LF  page 80 : A = P3V3_AUX ; B = PU_S3M_CPU0_CPLD_STATUS

(kicad_pcb
	(version 20260206)
	(generator "pcbnew")
	(generator_version "10.0")
	(general
		(thickness 1.6)
		(legacy_teardrops no)
	)
	(paper "A4")
	(title_block
		(title "03242023_DA0F0TMBIJ0_F0T_Motherboard_J_brd_V01_OCP.brd")
		(comment 1 "Grand Teton / footprints 5627-5629 of 6105")
	)
	(layers
		(0 "F.Cu" signal "TOP")
		(4 "In1.Cu" signal "GND")
		(6 "In2.Cu" signal "IN1")
		(8 "In3.Cu" signal "GND1")
		(10 "In4.Cu" signal "IN2")
		(12 "In5.Cu" signal "GND2")
		(14 "In6.Cu" signal "IN3")
		(16 "In7.Cu" signal "GND3")
		(18 "In8.Cu" signal "VCC")
		(20 "In9.Cu" signal "VCC1")
		(22 "In10.Cu" signal "GND4")
		(24 "In11.Cu" signal "IN4")
		(26 "In12.Cu" signal "GND5")
		(28 "In13.Cu" signal "IN5")
		(30 "In14.Cu" signal "GND6")
		(32 "In15.Cu" signal "IN6")
		(34 "In16.Cu" signal "GND7")
		(2 "B.Cu" signal "BOTTOM")
		(9 "F.Adhes" user "F.Adhesive")
		(11 "B.Adhes" user "B.Adhesive")
		(13 "F.Paste" user "Package Geometry/Pastemask Top")
		(15 "B.Paste" user "Package Geometry/Pastemask Bottom")
		(5 "F.SilkS" user "Ref Des/Silkscreen Top")
		(7 "B.SilkS" user "Ref Des/Silkscreen Bottom")
		(1 "F.Mask" user "Board Geometry/Soldermask Top")
		(3 "B.Mask" user "Board Geometry/Soldermask Bottom")
		(17 "Dwgs.User" user "User.Drawings")
		(19 "Cmts.User" user "User.Comments")
		(21 "Eco1.User" user "User.Eco1")
		(23 "Eco2.User" user "User.Eco2")
		(25 "Edge.Cuts" user "Board Geometry/Outline")
		(27 "Margin" user)
		(31 "F.CrtYd" user "Package Geometry/Place Bound Top")
		(29 "B.CrtYd" user "Package Geometry/Place Bound Bottom")
		(35 "F.Fab" user "Ref Des/Assembly Top")
		(33 "B.Fab" user "Ref Des/Assembly Bottom")
	)
	(footprint ""
		(layer "B.Cu")
		(at 415.271712 -193.08953 -90)
		(property "Reference" "R319"
			(at 0 0 90)
			(layer "B.SilkS")
			(hide yes)
			(effects
				(font
					(size 1.27 1.27)
				)
				(justify mirror)
			)
		)
		(property "Value" ""
			(at 0 0 90)
			(layer "B.Fab")
			(effects
				(font
					(size 1.27 1.27)
				)
				(justify mirror)
			)
		)
		(duplicate_pad_numbers_are_jumpers no)
		(fp_line
			(start -0.7874 0.4064)
			(end 0.7874 0.4064)
			(stroke
				(width 0.1524)
				(type default)
			)
			(layer "B.SilkS")
		)
		(fp_line
			(start 0.7874 0.4064)
			(end 0.7874 -0.4064)
			(stroke
				(width 0.1524)
				(type default)
			)
			(layer "B.SilkS")
		)
		(fp_line
			(start -0.7874 -0.4064)
			(end -0.7874 0.4064)
			(stroke
				(width 0.1524)
				(type default)
			)
			(layer "B.SilkS")
		)
		(fp_line
			(start 0.7874 -0.4064)
			(end -0.7874 -0.4064)
			(stroke
				(width 0.1524)
				(type default)
			)
			(layer "B.SilkS")
		)
		(fp_line
			(start -0.67945 0.3048)
			(end -0.120396 0.3048)
			(stroke
				(width 0.1)
				(type default)
			)
			(layer "B.Fab")
		)
		(fp_line
			(start -0.120396 0.3048)
			(end -0.120396 0.2794)
			(stroke
				(width 0.1)
				(type default)
			)
			(layer "B.Fab")
		)
		(fp_line
			(start 0.12065 0.3048)
			(end 0.67945 0.3048)
			(stroke
				(width 0.1)
				(type default)
			)
			(layer "B.Fab")
		)
		(fp_line
			(start 0.67945 0.3048)
			(end 0.67945 -0.305054)
			(stroke
				(width 0.1)
				(type default)
			)
			(layer "B.Fab")
		)
		(fp_line
			(start -0.120396 0.2794)
			(end 0.12065 0.2794)
			(stroke
				(width 0.1)
				(type default)
			)
			(layer "B.Fab")
		)
		(fp_line
			(start 0.12065 0.2794)
			(end 0.12065 0.3048)
			(stroke
				(width 0.1)
				(type default)
			)
			(layer "B.Fab")
		)
		(fp_line
			(start -0.12065 -0.2794)
			(end -0.12065 -0.3048)
			(stroke
				(width 0.1)
				(type default)
			)
			(layer "B.Fab")
		)
		(fp_line
			(start 0.12065 -0.2794)
			(end -0.12065 -0.2794)
			(stroke
				(width 0.1)
				(type default)
			)
			(layer "B.Fab")
		)
		(fp_line
			(start -0.67945 -0.3048)
			(end -0.67945 0.3048)
			(stroke
				(width 0.1)
				(type default)
			)
			(layer "B.Fab")
		)
		(fp_line
			(start -0.12065 -0.3048)
			(end -0.67945 -0.3048)
			(stroke
				(width 0.1)
				(type default)
			)
			(layer "B.Fab")
		)
		(fp_line
			(start 0.12065 -0.305054)
			(end 0.12065 -0.2794)
			(stroke
				(width 0.1)
				(type default)
			)
			(layer "B.Fab")
		)
		(fp_line
			(start 0.67945 -0.305054)
			(end 0.12065 -0.305054)
			(stroke
				(width 0.1)
				(type default)
			)
			(layer "B.Fab")
		)
		(pad "1" smd circle
			(at 0.40005 0 90)
			(size 0 0)
			(layers "B.Cu" "B.Mask" "B.Paste")
			(net "P3V3_AUX")
		)
		(pad "2" smd circle
			(at -0.40005 0 90)
			(size 0 0)
			(layers "B.Cu" "B.Mask" "B.Paste")
			(net "PU_S3M_CPU0_CPLD_STATUS")
		)
	)
	(footprint ""
		(layer "B.Cu")
		(at 366.120934 -244.820186 -90)
		(property "Reference" "C382"
			(at 0 0 90)
			(layer "B.SilkS")
			(hide yes)
			(effects
				(font
					(size 1.27 1.27)
				)
				(justify mirror)
			)
		)
		(property "Value" ""
			(at 0 0 90)
			(layer "B.Fab")
			(effects
				(font
					(size 1.27 1.27)
				)
				(justify mirror)
			)
		)
		(duplicate_pad_numbers_are_jumpers no)
		(fp_line
			(start -1.524 0.762)
			(end 1.524 0.762)
			(stroke
				(width 0.1524)
				(type default)
			)
			(layer "B.SilkS")
		)
		(fp_line
			(start 1.524 0.762)
			(end 1.524 -0.762)
			(stroke
				(width 0.1524)
				(type default)
			)
			(layer "B.SilkS")
		)
		(fp_line
			(start -1.524 -0.762)
			(end -1.524 0.762)
			(stroke
				(width 0.1524)
				(type default)
			)
			(layer "B.SilkS")
		)
		(fp_line
			(start 1.524 -0.762)
			(end -1.524 -0.762)
			(stroke
				(width 0.1524)
				(type default)
			)
			(layer "B.SilkS")
		)
		(fp_line
			(start -1.1049 0.724916)
			(end -1.1049 -0.724916)
			(stroke
				(width 0.1)
				(type default)
			)
			(layer "B.Fab")
		)
		(fp_line
			(start 1.1049 0.724916)
			(end -1.1049 0.724916)
			(stroke
				(width 0.1)
				(type default)
			)
			(layer "B.Fab")
		)
		(fp_line
			(start -1.1049 -0.724916)
			(end 1.1049 -0.724916)
			(stroke
				(width 0.1)
				(type default)
			)
			(layer "B.Fab")
		)
		(fp_line
			(start 1.1049 -0.724916)
			(end 1.1049 0.724916)
			(stroke
				(width 0.1)
				(type default)
			)
			(layer "B.Fab")
		)
		(pad "1" smd rect
			(at 0.889 0 270)
			(size 1.016 1.27)
			(layers "B.Cu" "B.Mask" "B.Paste")
			(net "PVCCIN_CPU0")
		)
		(pad "2" smd rect
			(at -0.889 0 270)
			(size 1.016 1.27)
			(layers "B.Cu" "B.Mask" "B.Paste")
			(net "GND")
		)
	)
	(footprint ""
		(layer "B.Cu")
		(at 298.626784 -356.036372 -90)
		(property "Reference" "PC2170"
			(at 0 0 90)
			(layer "B.SilkS")
			(hide yes)
			(effects
				(font
					(size 1.27 1.27)
				)
				(justify mirror)
			)
		)
		(property "Value" ""
			(at 0 0 90)
			(layer "B.Fab")
			(effects
				(font
					(size 1.27 1.27)
				)
				(justify mirror)
			)
		)
		(duplicate_pad_numbers_are_jumpers no)
		(fp_line
			(start -4.533392 2.249932)
			(end 4.533392 2.249932)
			(stroke
				(width 0.1524)
				(type default)
			)
			(layer "B.SilkS")
		)
		(fp_line
			(start 4.533392 2.249932)
			(end 4.533392 -2.249932)
			(stroke
				(width 0.1524)
				(type default)
			)
			(layer "B.SilkS")
		)
		(fp_line
			(start -4.533392 -2.249932)
			(end -4.533392 2.249932)
			(stroke
				(width 0.1524)
				(type default)
			)
			(layer "B.SilkS")
		)
		(fp_line
			(start 4.533392 -2.249932)
			(end -4.533392 -2.249932)
			(stroke
				(width 0.1524)
				(type default)
			)
			(layer "B.SilkS")
		)
		(fp_poly
			(pts
				(xy 4.533392 -2.326132) (xy 5.39242 -2.326132) (xy 5.39242 2.326132) (xy 4.533392 2.326132)
			)
			(stroke
				(width 0)
				(type default)
			)
			(fill yes)
			(layer "B.SilkS")
		)
		(fp_line
			(start -3.750056 2.249932)
			(end 3.750056 2.249932)
			(stroke
				(width 0.1)
				(type default)
			)
			(layer "B.Fab")
		)
		(fp_line
			(start 3.750056 2.249932)
			(end 3.750056 -2.249932)
			(stroke
				(width 0.1)
				(type default)
			)
			(layer "B.Fab")
		)
		(fp_line
			(start -3.750056 -2.249932)
			(end -3.750056 2.249932)
			(stroke
				(width 0.1)
				(type default)
			)
			(layer "B.Fab")
		)
		(fp_line
			(start 3.750056 -2.249932)
			(end -3.750056 -2.249932)
			(stroke
				(width 0.1)
				(type default)
			)
			(layer "B.Fab")
		)
		(fp_text user "+"
			(at 6.322314 0.786384 180)
			(unlocked yes)
			(layer "B.SilkS")
			(effects
				(font
					(size 1.905 1.4224)
					(thickness 0.1524)
				)
				(justify left mirror)
			)
		)
		(fp_text user "-"
			(at -4.8514 -0.14605 270)
			(unlocked yes)
			(layer "B.SilkS")
			(effects
				(font
					(size 1.905 1.4224)
					(thickness 0.1524)
				)
				(justify left mirror)
			)
		)
		(fp_text user "+"
			(at 6.322314 0.786384 180)
			(unlocked yes)
			(layer "B.Fab")
			(effects
				(font
					(size 1.905 1.4224)
					(thickness 0.1524)
				)
				(justify left mirror)
			)
		)
		(fp_text user "-"
			(at -4.8514 -0.14605 270)
			(unlocked yes)
			(layer "B.Fab")
			(effects
				(font
					(size 1.905 1.4224)
					(thickness 0.1524)
				)
				(justify left mirror)
			)
		)
		(pad "1" smd rect
			(at 3.199892 0 90)
			(size 2.413 2.8194)
			(layers "B.Cu" "B.Mask" "B.Paste")
			(net "PVCCFA_EHV_FIVRA_CPU0")
		)
		(pad "2" smd rect
			(at -3.199892 0 90)
			(size 2.413 2.8194)
			(layers "B.Cu" "B.Mask" "B.Paste")
			(net "GND")
		)
	)
)
